# S9S_MB_2U (Grand Teton) — schematic netlist excerpt (pin names and nets, part order shuffled) for the footprints in the layout excerpt that follows; sources: Cadence DE-HDL packaged netlist, KiCad conversion of 03242023_DA0F0TMBIJ0_F0T_Motherboard_J_brd_V01_OCP.brd

C1344  Q_CAP  100PF 50V 5% EMPTY  pkg 0402  page 250 : A = P12V_AUX_ADC_MAM ; B = GND
C1279  Q_CAP  0.1UF 25V 10% X7R  pkg 0402  page 191 : A = P12V_E1S_0 ; B = GND

(kicad_pcb
	(version 20260206)
	(generator "pcbnew")
	(generator_version "10.0")
	(general
		(thickness 1.6)
		(legacy_teardrops no)
	)
	(paper "A4")
	(title_block
		(title "03242023_DA0F0TMBIJ0_F0T_Motherboard_J_brd_V01_OCP.brd")
		(comment 1 "Grand Teton / footprints 1781-1782 of 6105")
	)
	(layers
		(0 "F.Cu" signal "TOP")
		(4 "In1.Cu" signal "GND")
		(6 "In2.Cu" signal "IN1")
		(8 "In3.Cu" signal "GND1")
		(10 "In4.Cu" signal "IN2")
		(12 "In5.Cu" signal "GND2")
		(14 "In6.Cu" signal "IN3")
		(16 "In7.Cu" signal "GND3")
		(18 "In8.Cu" signal "VCC")
		(20 "In9.Cu" signal "VCC1")
		(22 "In10.Cu" signal "GND4")
		(24 "In11.Cu" signal "IN4")
		(26 "In12.Cu" signal "GND5")
		(28 "In13.Cu" signal "IN5")
		(30 "In14.Cu" signal "GND6")
		(32 "In15.Cu" signal "IN6")
		(34 "In16.Cu" signal "GND7")
		(2 "B.Cu" signal "BOTTOM")
		(9 "F.Adhes" user "F.Adhesive")
		(11 "B.Adhes" user "B.Adhesive")
		(13 "F.Paste" user "Package Geometry/Pastemask Top")
		(15 "B.Paste" user "Package Geometry/Pastemask Bottom")
		(5 "F.SilkS" user "Ref Des/Silkscreen Top")
		(7 "B.SilkS" user "Ref Des/Silkscreen Bottom")
		(1 "F.Mask" user "Board Geometry/Soldermask Top")
		(3 "B.Mask" user "Board Geometry/Soldermask Bottom")
		(17 "Dwgs.User" user "User.Drawings")
		(19 "Cmts.User" user "User.Comments")
		(21 "Eco1.User" user "User.Eco1")
		(23 "Eco2.User" user "User.Eco2")
		(25 "Edge.Cuts" user "Board Geometry/Outline")
		(27 "Margin" user)
		(31 "F.CrtYd" user "Package Geometry/Place Bound Top")
		(29 "B.CrtYd" user "Package Geometry/Place Bound Bottom")
		(35 "F.Fab" user "Ref Des/Assembly Top")
		(33 "B.Fab" user "Ref Des/Assembly Bottom")
	)
	(footprint ""
		(layer "F.Cu")
		(at 243.084858 -50.138838 90)
		(property "Reference" "C1279"
			(at 0 0 90)
			(layer "F.SilkS")
			(hide yes)
			(effects
				(font
					(size 1.27 1.27)
				)
			)
		)
		(property "Value" ""
			(at 0 0 90)
			(layer "F.Fab")
			(effects
				(font
					(size 1.27 1.27)
				)
			)
		)
		(duplicate_pad_numbers_are_jumpers no)
		(fp_line
			(start 0.7874 -0.4064)
			(end 0.7874 0.4064)
			(stroke
				(width 0.1524)
				(type default)
			)
			(layer "F.SilkS")
		)
		(fp_line
			(start -0.7874 -0.4064)
			(end 0.7874 -0.4064)
			(stroke
				(width 0.1524)
				(type default)
			)
			(layer "F.SilkS")
		)
		(fp_line
			(start 0.7874 0.4064)
			(end -0.7874 0.4064)
			(stroke
				(width 0.1524)
				(type default)
			)
			(layer "F.SilkS")
		)
		(fp_line
			(start -0.7874 0.4064)
			(end -0.7874 -0.4064)
			(stroke
				(width 0.1524)
				(type default)
			)
			(layer "F.SilkS")
		)
		(fp_line
			(start -0.12065 -0.305054)
			(end -0.12065 -0.2794)
			(stroke
				(width 0.1)
				(type default)
			)
			(layer "F.Fab")
		)
		(fp_line
			(start -0.67945 -0.305054)
			(end -0.12065 -0.305054)
			(stroke
				(width 0.1)
				(type default)
			)
			(layer "F.Fab")
		)
		(fp_line
			(start 0.67945 -0.3048)
			(end 0.67945 0.3048)
			(stroke
				(width 0.1)
				(type default)
			)
			(layer "F.Fab")
		)
		(fp_line
			(start 0.12065 -0.3048)
			(end 0.67945 -0.3048)
			(stroke
				(width 0.1)
				(type default)
			)
			(layer "F.Fab")
		)
		(fp_line
			(start 0.12065 -0.2794)
			(end 0.12065 -0.3048)
			(stroke
				(width 0.1)
				(type default)
			)
			(layer "F.Fab")
		)
		(fp_line
			(start -0.12065 -0.2794)
			(end 0.12065 -0.2794)
			(stroke
				(width 0.1)
				(type default)
			)
			(layer "F.Fab")
		)
		(fp_line
			(start 0.120396 0.2794)
			(end -0.12065 0.2794)
			(stroke
				(width 0.1)
				(type default)
			)
			(layer "F.Fab")
		)
		(fp_line
			(start -0.12065 0.2794)
			(end -0.12065 0.3048)
			(stroke
				(width 0.1)
				(type default)
			)
			(layer "F.Fab")
		)
		(fp_line
			(start 0.67945 0.3048)
			(end 0.120396 0.3048)
			(stroke
				(width 0.1)
				(type default)
			)
			(layer "F.Fab")
		)
		(fp_line
			(start 0.120396 0.3048)
			(end 0.120396 0.2794)
			(stroke
				(width 0.1)
				(type default)
			)
			(layer "F.Fab")
		)
		(fp_line
			(start -0.12065 0.3048)
			(end -0.67945 0.3048)
			(stroke
				(width 0.1)
				(type default)
			)
			(layer "F.Fab")
		)
		(fp_line
			(start -0.67945 0.3048)
			(end -0.67945 -0.305054)
			(stroke
				(width 0.1)
				(type default)
			)
			(layer "F.Fab")
		)
		(pad "1" smd circle
			(at -0.40005 0 90)
			(size 0 0)
			(layers "F.Cu" "F.Mask" "F.Paste")
			(net "P12V_E1S_0")
		)
		(pad "2" smd circle
			(at 0.40005 0 90)
			(size 0 0)
			(layers "F.Cu" "F.Mask" "F.Paste")
			(net "GND")
		)
	)
	(footprint ""
		(layer "F.Cu")
		(at 32.761428 -100.602034 180)
		(property "Reference" "C1344"
			(at 0 0 180)
			(layer "F.SilkS")
			(hide yes)
			(effects
				(font
					(size 1.27 1.27)
				)
			)
		)
		(property "Value" ""
			(at 0 0 180)
			(layer "F.Fab")
			(effects
				(font
					(size 1.27 1.27)
				)
			)
		)
		(duplicate_pad_numbers_are_jumpers no)
		(fp_line
			(start 0.7874 0.4064)
			(end -0.7874 0.4064)
			(stroke
				(width 0.1524)
				(type default)
			)
			(layer "F.SilkS")
		)
		(fp_line
			(start 0.7874 -0.4064)
			(end 0.7874 0.4064)
			(stroke
				(width 0.1524)
				(type default)
			)
			(layer "F.SilkS")
		)
		(fp_line
			(start -0.7874 0.4064)
			(end -0.7874 -0.4064)
			(stroke
				(width 0.1524)
				(type default)
			)
			(layer "F.SilkS")
		)
		(fp_line
			(start -0.7874 -0.4064)
			(end 0.7874 -0.4064)
			(stroke
				(width 0.1524)
				(type default)
			)
			(layer "F.SilkS")
		)
		(fp_line
			(start 0.67945 0.3048)
			(end 0.120396 0.3048)
			(stroke
				(width 0.1)
				(type default)
			)
			(layer "F.Fab")
		)
		(fp_line
			(start 0.67945 -0.3048)
			(end 0.67945 0.3048)
			(stroke
				(width 0.1)
				(type default)
			)
			(layer "F.Fab")
		)
		(fp_line
			(start 0.12065 -0.2794)
			(end 0.12065 -0.3048)
			(stroke
				(width 0.1)
				(type default)
			)
			(layer "F.Fab")
		)
		(fp_line
			(start 0.12065 -0.3048)
			(end 0.67945 -0.3048)
			(stroke
				(width 0.1)
				(type default)
			)
			(layer "F.Fab")
		)
		(fp_line
			(start 0.120396 0.3048)
			(end 0.120396 0.2794)
			(stroke
				(width 0.1)
				(type default)
			)
			(layer "F.Fab")
		)
		(fp_line
			(start 0.120396 0.2794)
			(end -0.12065 0.2794)
			(stroke
				(width 0.1)
				(type default)
			)
			(layer "F.Fab")
		)
		(fp_line
			(start -0.12065 0.3048)
			(end -0.67945 0.3048)
			(stroke
				(width 0.1)
				(type default)
			)
			(layer "F.Fab")
		)
		(fp_line
			(start -0.12065 0.2794)
			(end -0.12065 0.3048)
			(stroke
				(width 0.1)
				(type default)
			)
			(layer "F.Fab")
		)
		(fp_line
			(start -0.12065 -0.2794)
			(end 0.12065 -0.2794)
			(stroke
				(width 0.1)
				(type default)
			)
			(layer "F.Fab")
		)
		(fp_line
			(start -0.12065 -0.305054)
			(end -0.12065 -0.2794)
			(stroke
				(width 0.1)
				(type default)
			)
			(layer "F.Fab")
		)
		(fp_line
			(start -0.67945 0.3048)
			(end -0.67945 -0.305054)
			(stroke
				(width 0.1)
				(type default)
			)
			(layer "F.Fab")
		)
		(fp_line
			(start -0.67945 -0.305054)
			(end -0.12065 -0.305054)
			(stroke
				(width 0.1)
				(type default)
			)
			(layer "F.Fab")
		)
		(pad "1" smd circle
			(at -0.40005 0 180)
			(size 0 0)
			(layers "F.Cu" "F.Mask" "F.Paste")
			(net "P12V_AUX_ADC_MAM")
		)
		(pad "2" smd circle
			(at 0.40005 0 180)
			(size 0 0)
			(layers "F.Cu" "F.Mask" "F.Paste")
			(net "GND")
		)
	)
)
